(kicad_pcb
	(version 20260206)
	(generator "pcbnew")
	(generator_version "10.0")
	(general
		(thickness 1.6)
		(legacy_teardrops no)
	)
	(paper "A4")
	(title_block
		(title "Bryce Canyon_F.DPB_16315-1-OCP.brd")
		(comment 1 "Bryce Canyon / footprints 570-577 of 2223")
	)
	(layers
		(0 "F.Cu" signal "TOP")
		(4 "In1.Cu" signal "L2GND")
		(6 "In2.Cu" signal "L3")
		(8 "In3.Cu" signal "L4GND")
		(10 "In4.Cu" signal "L5")
		(12 "In5.Cu" signal "L6VCC")
		(14 "In6.Cu" signal "L7VCC")
		(16 "In7.Cu" signal "L8")
		(18 "In8.Cu" signal "L9GND")
		(20 "In9.Cu" signal "L10")
		(22 "In10.Cu" signal "L11GND")
		(2 "B.Cu" signal "BOTTOM")
		(9 "F.Adhes" user "F.Adhesive")
		(11 "B.Adhes" user "B.Adhesive")
		(13 "F.Paste" user "Package Geometry/Pastemask Top")
		(15 "B.Paste" user "Package Geometry/Pastemask Bottom")
		(5 "F.SilkS" user "Ref Des/Silkscreen Top")
		(7 "B.SilkS" user "Ref Des/Silkscreen Bottom")
		(1 "F.Mask" user "Board Geometry/Soldermask Top")
		(3 "B.Mask" user "Board Geometry/Soldermask Bottom")
		(17 "Dwgs.User" user "User.Drawings")
		(19 "Cmts.User" user "User.Comments")
		(21 "Eco1.User" user "User.Eco1")
		(23 "Eco2.User" user "User.Eco2")
		(25 "Edge.Cuts" user "Board Geometry/Outline")
		(27 "Margin" user)
		(31 "F.CrtYd" user "Package Geometry/Place Bound Top")
		(29 "B.CrtYd" user "Package Geometry/Place Bound Bottom")
		(35 "F.Fab" user "Ref Des/Assembly Top")
		(33 "B.Fab" user "Ref Des/Assembly Bottom")
	)
	(footprint ""
		(layer "F.Cu")
		(at 427.390052 -279.596342 90)
		(property "Reference" "C165"
			(at 0 0 90)
			(layer "F.SilkS")
			(hide yes)
			(effects
				(font
					(size 1.27 1.27)
				)
			)
		)
		(property "Value" "SCD033U25V2KX-GP"
			(at 1.1811 -2.7051 90)
			(unlocked yes)
			(layer "F.Fab")
			(hide yes)
			(effects
				(font
					(size 1.016 1.016)
					(thickness 0.1524)
				)
			)
		)
		(property "Device Type" "C402H22"
			(at 1.1811 -4.2291 90)
			(unlocked yes)
			(layer "F.Fab")
			(hide yes)
			(effects
				(font
					(size 1.016 1.016)
					(thickness 0.1524)
				)
			)
		)
		(duplicate_pad_numbers_are_jumpers no)
		(fp_rect
			(start -0.4318 0.9525)
			(end 0.4318 -0.9525)
			(stroke
				(width 0)
				(type default)
			)
			(fill no)
			(layer "F.CrtYd")
		)
		(fp_rect
			(start -0.4318 0.9525)
			(end 0.4318 -0.9525)
			(stroke
				(width 0)
				(type default)
			)
			(fill no)
			(layer "F.Fab")
		)
		(pad "1" smd custom
			(at 0 -0.4445 90)
			(size 0.1524 0.1524)
			(layers "F.Cu" "F.Mask" "F.Paste")
			(net "SW_HDD_P9")
			(options
				(clearance outline)
				(anchor circle)
			)
			(primitives
				(gr_poly
					(pts
						(arc
							(start 0.3048 -0.2032)
							(mid 0.275042 -0.275042)
							(end 0.2032 -0.3048)
						)
						(arc
							(start -0.2032 -0.3048)
							(mid -0.275042 -0.275042)
							(end -0.3048 -0.2032)
						)
						(arc
							(start -0.3048 0.2032)
							(mid -0.275042 0.275042)
							(end -0.2032 0.3048)
						)
						(arc
							(start 0.2032 0.3048)
							(mid 0.275042 0.275042)
							(end 0.3048 0.2032)
						)
					)
					(width 0)
					(fill yes)
				)
			)
		)
		(pad "2" smd custom
			(at 0 0.4445 90)
			(size 0.1524 0.1524)
			(layers "F.Cu" "F.Mask" "F.Paste")
			(net "GND")
			(options
				(clearance outline)
				(anchor circle)
			)
			(primitives
				(gr_poly
					(pts
						(arc
							(start 0.3048 -0.2032)
							(mid 0.275042 -0.275042)
							(end 0.2032 -0.3048)
						)
						(arc
							(start -0.2032 -0.3048)
							(mid -0.275042 -0.275042)
							(end -0.3048 -0.2032)
						)
						(arc
							(start -0.3048 0.2032)
							(mid -0.275042 0.275042)
							(end -0.2032 0.3048)
						)
						(arc
							(start 0.2032 0.3048)
							(mid 0.275042 0.275042)
							(end 0.3048 0.2032)
						)
					)
					(width 0)
					(fill yes)
				)
			)
		)
	)
	(footprint ""
		(layer "F.Cu")
		(at 272.34007 -9.901428 180)
		(property "Reference" "TP192"
			(at 0 0 180)
			(layer "F.SilkS")
			(hide yes)
			(effects
				(font
					(size 1.27 1.27)
				)
			)
		)
		(property "Value" "TPAD32-GP"
			(at -0.0508 -1.6764 180)
			(unlocked yes)
			(layer "F.Fab")
			(hide yes)
			(effects
				(font
					(size 1.016 1.016)
					(thickness 0.1524)
				)
			)
		)
		(property "Device Type" "TPAD32"
			(at -0.0508 -3.2004 180)
			(unlocked yes)
			(layer "F.Fab")
			(hide yes)
			(effects
				(font
					(size 1.016 1.016)
					(thickness 0.1524)
				)
			)
		)
		(duplicate_pad_numbers_are_jumpers no)
		(fp_poly
			(pts
				(arc
					(start -0.4064 0)
					(mid 0.4064 0)
					(end -0.4064 0)
				)
			)
			(stroke
				(width 0)
				(type default)
			)
			(fill no)
			(layer "F.CrtYd")
		)
		(fp_poly
			(pts
				(arc
					(start -0.7112 0)
					(mid 0.7112 0)
					(end -0.7112 0)
				)
			)
			(stroke
				(width 0)
				(type default)
			)
			(fill no)
			(layer "F.Fab")
		)
		(pad "1" smd circle
			(at 0 0 180)
			(size 0.8128 0.8128)
			(layers "F.Cu" "F.Mask" "F.Paste")
			(net "TP_COMP_B_NCSI_TXD0")
		)
	)
	(footprint ""
		(layer "F.Cu")
		(at 471.924126 -168.126918 -90)
		(property "Reference" "C347"
			(at 0 0 270)
			(layer "F.SilkS")
			(hide yes)
			(effects
				(font
					(size 1.27 1.27)
				)
			)
		)
		(property "Value" "SCD033U25V2KX-GP"
			(at 1.1811 -2.7051 270)
			(unlocked yes)
			(layer "F.Fab")
			(hide yes)
			(effects
				(font
					(size 1.016 1.016)
					(thickness 0.1524)
				)
			)
		)
		(property "Device Type" "C402H22"
			(at 1.1811 -4.2291 270)
			(unlocked yes)
			(layer "F.Fab")
			(hide yes)
			(effects
				(font
					(size 1.016 1.016)
					(thickness 0.1524)
				)
			)
		)
		(duplicate_pad_numbers_are_jumpers no)
		(fp_rect
			(start -0.4318 0.9525)
			(end 0.4318 -0.9525)
			(stroke
				(width 0)
				(type default)
			)
			(fill no)
			(layer "F.CrtYd")
		)
		(fp_rect
			(start -0.4318 0.9525)
			(end 0.4318 -0.9525)
			(stroke
				(width 0)
				(type default)
			)
			(fill no)
			(layer "F.Fab")
		)
		(pad "1" smd custom
			(at 0 -0.4445 270)
			(size 0.1524 0.1524)
			(layers "F.Cu" "F.Mask" "F.Paste")
			(net "SW_HDD_P23")
			(options
				(clearance outline)
				(anchor circle)
			)
			(primitives
				(gr_poly
					(pts
						(arc
							(start 0.3048 -0.2032)
							(mid 0.275042 -0.275042)
							(end 0.2032 -0.3048)
						)
						(arc
							(start -0.2032 -0.3048)
							(mid -0.275042 -0.275042)
							(end -0.3048 -0.2032)
						)
						(arc
							(start -0.3048 0.2032)
							(mid -0.275042 0.275042)
							(end -0.2032 0.3048)
						)
						(arc
							(start 0.2032 0.3048)
							(mid 0.275042 0.275042)
							(end 0.3048 0.2032)
						)
					)
					(width 0)
					(fill yes)
				)
			)
		)
		(pad "2" smd custom
			(at 0 0.4445 270)
			(size 0.1524 0.1524)
			(layers "F.Cu" "F.Mask" "F.Paste")
			(net "GND")
			(options
				(clearance outline)
				(anchor circle)
			)
			(primitives
				(gr_poly
					(pts
						(arc
							(start 0.3048 -0.2032)
							(mid 0.275042 -0.275042)
							(end 0.2032 -0.3048)
						)
						(arc
							(start -0.2032 -0.3048)
							(mid -0.275042 -0.275042)
							(end -0.3048 -0.2032)
						)
						(arc
							(start -0.3048 0.2032)
							(mid -0.275042 0.275042)
							(end -0.2032 0.3048)
						)
						(arc
							(start 0.2032 0.3048)
							(mid 0.275042 0.275042)
							(end 0.3048 0.2032)
						)
					)
					(width 0)
					(fill yes)
				)
			)
		)
	)
	(footprint ""
		(layer "F.Cu")
		(at 134.283196 -292.804342 90)
		(property "Reference" "C79"
			(at 0 0 90)
			(layer "F.SilkS")
			(hide yes)
			(effects
				(font
					(size 1.27 1.27)
				)
			)
		)
		(property "Value" "SC1U16V3KX-5GP"
			(at 0 -2.8194 90)
			(unlocked yes)
			(layer "F.Fab")
			(hide yes)
			(effects
				(font
					(size 1.016 1.016)
					(thickness 0.1524)
				)
			)
		)
		(property "Device Type" "C603H36"
			(at 0 -4.3434 90)
			(unlocked yes)
			(layer "F.Fab")
			(hide yes)
			(effects
				(font
					(size 1.016 1.016)
					(thickness 0.1524)
				)
			)
		)
		(duplicate_pad_numbers_are_jumpers no)
		(fp_line
			(start 0.508 0)
			(end -0.508 0)
			(stroke
				(width 0.2032)
				(type default)
			)
			(layer "F.SilkS")
		)
		(fp_rect
			(start -0.5842 1.3335)
			(end 0.5842 -1.3335)
			(stroke
				(width 0)
				(type default)
			)
			(fill no)
			(layer "F.CrtYd")
		)
		(fp_rect
			(start -0.5842 1.3335)
			(end 0.5842 -1.3335)
			(stroke
				(width 0)
				(type default)
			)
			(fill no)
			(layer "F.Fab")
		)
		(pad "1" smd custom
			(at 0 -0.762 90)
			(size 0.2159 0.2159)
			(layers "F.Cu" "F.Mask" "F.Paste")
			(net "P5V_HDD3")
			(options
				(clearance outline)
				(anchor circle)
			)
			(primitives
				(gr_poly
					(pts
						(arc
							(start -0.3302 -0.4318)
							(mid -0.402042 -0.402042)
							(end -0.4318 -0.3302)
						)
						(arc
							(start -0.4318 0.3302)
							(mid -0.402042 0.402042)
							(end -0.3302 0.4318)
						)
						(arc
							(start 0.3302 0.4318)
							(mid 0.402042 0.402042)
							(end 0.4318 0.3302)
						)
						(arc
							(start 0.4318 -0.3302)
							(mid 0.402042 -0.402042)
							(end 0.3302 -0.4318)
						)
					)
					(width 0)
					(fill yes)
				)
			)
		)
		(pad "2" smd custom
			(at 0 0.762 90)
			(size 0.2159 0.2159)
			(layers "F.Cu" "F.Mask" "F.Paste")
			(net "GND")
			(options
				(clearance outline)
				(anchor circle)
			)
			(primitives
				(gr_poly
					(pts
						(arc
							(start -0.3302 -0.4318)
							(mid -0.402042 -0.402042)
							(end -0.4318 -0.3302)
						)
						(arc
							(start -0.4318 0.3302)
							(mid -0.402042 0.402042)
							(end -0.3302 0.4318)
						)
						(arc
							(start 0.3302 0.4318)
							(mid 0.402042 0.402042)
							(end 0.4318 0.3302)
						)
						(arc
							(start 0.4318 -0.3302)
							(mid 0.402042 -0.402042)
							(end 0.3302 -0.4318)
						)
					)
					(width 0)
					(fill yes)
				)
			)
		)
	)
	(footprint ""
		(layer "F.Cu")
		(at 349.565722 -146.435826)
		(property "Reference" "C565"
			(at 0 0 0)
			(layer "F.SilkS")
			(hide yes)
			(effects
				(font
					(size 1.27 1.27)
				)
			)
		)
		(property "Value" "SCD1U25V2KX-2-GP"
			(at 1.1811 -2.7051 0)
			(unlocked yes)
			(layer "F.Fab")
			(hide yes)
			(effects
				(font
					(size 1.016 1.016)
					(thickness 0.1524)
				)
			)
		)
		(property "Device Type" "C402H22"
			(at 1.1811 -4.2291 0)
			(unlocked yes)
			(layer "F.Fab")
			(hide yes)
			(effects
				(font
					(size 1.016 1.016)
					(thickness 0.1524)
				)
			)
		)
		(duplicate_pad_numbers_are_jumpers no)
		(fp_rect
			(start -0.4318 0.9525)
			(end 0.4318 -0.9525)
			(stroke
				(width 0)
				(type default)
			)
			(fill no)
			(layer "F.CrtYd")
		)
		(fp_rect
			(start -0.4318 0.9525)
			(end 0.4318 -0.9525)
			(stroke
				(width 0)
				(type default)
			)
			(fill no)
			(layer "F.Fab")
		)
		(pad "1" smd custom
			(at 0 -0.4445)
			(size 0.1524 0.1524)
			(layers "F.Cu" "F.Mask" "F.Paste")
			(net "P12V_B")
			(options
				(clearance outline)
				(anchor circle)
			)
			(primitives
				(gr_poly
					(pts
						(arc
							(start 0.3048 -0.2032)
							(mid 0.275042 -0.275042)
							(end 0.2032 -0.3048)
						)
						(arc
							(start -0.2032 -0.3048)
							(mid -0.275042 -0.275042)
							(end -0.3048 -0.2032)
						)
						(arc
							(start -0.3048 0.2032)
							(mid -0.275042 0.275042)
							(end -0.2032 0.3048)
						)
						(arc
							(start 0.2032 0.3048)
							(mid 0.275042 0.275042)
							(end 0.3048 0.2032)
						)
					)
					(width 0)
					(fill yes)
				)
			)
		)
		(pad "2" smd custom
			(at 0 0.4445)
			(size 0.1524 0.1524)
			(layers "F.Cu" "F.Mask" "F.Paste")
			(net "GND")
			(options
				(clearance outline)
				(anchor circle)
			)
			(primitives
				(gr_poly
					(pts
						(arc
							(start 0.3048 -0.2032)
							(mid 0.275042 -0.275042)
							(end 0.2032 -0.3048)
						)
						(arc
							(start -0.2032 -0.3048)
							(mid -0.275042 -0.275042)
							(end -0.3048 -0.2032)
						)
						(arc
							(start -0.3048 0.2032)
							(mid -0.275042 0.275042)
							(end -0.2032 0.3048)
						)
						(arc
							(start 0.2032 0.3048)
							(mid 0.275042 0.275042)
							(end 0.3048 0.2032)
						)
					)
					(width 0)
					(fill yes)
				)
			)
		)
	)
	(footprint ""
		(layer "F.Cu")
		(at 190.8048 -53.2384 90)
		(property "Reference" "C423"
			(at 0 0 90)
			(layer "F.SilkS")
			(hide yes)
			(effects
				(font
					(size 1.27 1.27)
				)
			)
		)
		(property "Value" "SCD01U50V2KX-1GP"
			(at 1.1811 -2.7051 90)
			(unlocked yes)
			(layer "F.Fab")
			(hide yes)
			(effects
				(font
					(size 1.016 1.016)
					(thickness 0.1524)
				)
			)
		)
		(property "Device Type" "C402H22"
			(at 1.1811 -4.2291 90)
			(unlocked yes)
			(layer "F.Fab")
			(hide yes)
			(effects
				(font
					(size 1.016 1.016)
					(thickness 0.1524)
				)
			)
		)
		(duplicate_pad_numbers_are_jumpers no)
		(fp_rect
			(start -0.4318 0.9525)
			(end 0.4318 -0.9525)
			(stroke
				(width 0)
				(type default)
			)
			(fill no)
			(layer "F.CrtYd")
		)
		(fp_rect
			(start -0.4318 0.9525)
			(end 0.4318 -0.9525)
			(stroke
				(width 0)
				(type default)
			)
			(fill no)
			(layer "F.Fab")
		)
		(pad "1" smd custom
			(at 0 -0.4445 90)
			(size 0.1524 0.1524)
			(layers "F.Cu" "F.Mask" "F.Paste")
			(net "HDD_PRSNT_29")
			(options
				(clearance outline)
				(anchor circle)
			)
			(primitives
				(gr_poly
					(pts
						(arc
							(start 0.3048 -0.2032)
							(mid 0.275042 -0.275042)
							(end 0.2032 -0.3048)
						)
						(arc
							(start -0.2032 -0.3048)
							(mid -0.275042 -0.275042)
							(end -0.3048 -0.2032)
						)
						(arc
							(start -0.3048 0.2032)
							(mid -0.275042 0.275042)
							(end -0.2032 0.3048)
						)
						(arc
							(start 0.2032 0.3048)
							(mid 0.275042 0.275042)
							(end 0.3048 0.2032)
						)
					)
					(width 0)
					(fill yes)
				)
			)
		)
		(pad "2" smd custom
			(at 0 0.4445 90)
			(size 0.1524 0.1524)
			(layers "F.Cu" "F.Mask" "F.Paste")
			(net "GND")
			(options
				(clearance outline)
				(anchor circle)
			)
			(primitives
				(gr_poly
					(pts
						(arc
							(start 0.3048 -0.2032)
							(mid 0.275042 -0.275042)
							(end 0.2032 -0.3048)
						)
						(arc
							(start -0.2032 -0.3048)
							(mid -0.275042 -0.275042)
							(end -0.3048 -0.2032)
						)
						(arc
							(start -0.3048 0.2032)
							(mid -0.275042 0.275042)
							(end -0.2032 0.3048)
						)
						(arc
							(start 0.2032 0.3048)
							(mid 0.275042 0.275042)
							(end 0.3048 0.2032)
						)
					)
					(width 0)
					(fill yes)
				)
			)
		)
	)
	(footprint ""
		(layer "F.Cu")
		(at 116.121942 -275.291804 90)
		(property "Reference" "Q19"
			(at 0 0 90)
			(layer "F.SilkS")
			(hide yes)
			(effects
				(font
					(size 1.27 1.27)
				)
			)
		)
		(property "Value" "2N7002KDW-GP"
			(at -2.3622 -8.2042 90)
			(unlocked yes)
			(layer "F.Fab")
			(hide yes)
			(effects
				(font
					(size 1.016 1.016)
					(thickness 0.1524)
				)
			)
		)
		(property "Device Type" "SOT-363H44"
			(at -2.3622 -10.1092 90)
			(unlocked yes)
			(layer "F.Fab")
			(hide yes)
			(effects
				(font
					(size 1.016 1.016)
					(thickness 0.1524)
				)
			)
		)
		(duplicate_pad_numbers_are_jumpers no)
		(fp_line
			(start 1.4478 -1.7018)
			(end -1.4478 -1.7018)
			(stroke
				(width 0.1524)
				(type default)
			)
			(layer "F.SilkS")
		)
		(fp_line
			(start -1.4478 -1.7018)
			(end -1.4478 1.7018)
			(stroke
				(width 0.1524)
				(type default)
			)
			(layer "F.SilkS")
		)
		(fp_line
			(start -1.27 1.524)
			(end -1.27 0.6604)
			(stroke
				(width 0.4826)
				(type default)
			)
			(layer "F.SilkS")
		)
		(fp_line
			(start 1.4478 1.7018)
			(end 1.4478 -1.7018)
			(stroke
				(width 0.1524)
				(type default)
			)
			(layer "F.SilkS")
		)
		(fp_line
			(start -1.4478 1.7018)
			(end 1.4478 1.7018)
			(stroke
				(width 0.1524)
				(type default)
			)
			(layer "F.SilkS")
		)
		(fp_poly
			(pts
				(xy -1.524 -1.778) (xy 1.524 -1.778) (xy 1.524 1.778) (xy -1.524 1.778)
			)
			(stroke
				(width 0)
				(type default)
			)
			(fill no)
			(layer "F.CrtYd")
		)
		(fp_poly
			(pts
				(xy -1.524 -1.778) (xy 1.524 -1.778) (xy 1.524 1.778) (xy -1.524 1.778)
			)
			(stroke
				(width 0)
				(type default)
			)
			(fill no)
			(layer "F.Fab")
		)
		(pad "1" smd rect
			(at -0.65024 0.9398 90)
			(size 0.4064 1.016)
			(layers "F.Cu" "F.Mask" "F.Paste")
			(net "GND")
		)
		(pad "2" smd rect
			(at 0 0.9398 90)
			(size 0.4064 1.016)
			(layers "F.Cu" "F.Mask" "F.Paste")
			(net "SW_PWR_R_HDD3")
		)
		(pad "3" smd rect
			(at 0.65024 0.9398 90)
			(size 0.4064 1.016)
			(layers "F.Cu" "F.Mask" "F.Paste")
			(net "SW_HDD_P3")
		)
		(pad "4" smd rect
			(at 0.65024 -0.9398 90)
			(size 0.4064 1.016)
			(layers "F.Cu" "F.Mask" "F.Paste")
			(net "GND")
		)
		(pad "5" smd rect
			(at 0 -0.9398 90)
			(size 0.4064 1.016)
			(layers "F.Cu" "F.Mask" "F.Paste")
			(net "SW_HDD_G3")
		)
		(pad "6" smd rect
			(at -0.65024 -0.9398 90)
			(size 0.4064 1.016)
			(layers "F.Cu" "F.Mask" "F.Paste")
			(net "SW_HDD_R3")
		)
	)
	(footprint ""
		(layer "F.Cu")
		(at 384.734562 -158.660592 -90)
		(property "Reference" "C299"
			(at 0 0 270)
			(layer "F.SilkS")
			(hide yes)
			(effects
				(font
					(size 1.27 1.27)
				)
			)
		)
		(property "Value" "SCD01U16V1KX-GP"
			(at -2.8321 -1.7399 270)
			(unlocked yes)
			(layer "F.Fab")
			(hide yes)
			(effects
				(font
					(size 1.016 1.016)
					(thickness 0.1524)
				)
			)
		)
		(property "Device Type" "C0201H13"
			(at -2.8321 -3.2639 270)
			(unlocked yes)
			(layer "F.Fab")
			(hide yes)
			(effects
				(font
					(size 1.016 1.016)
					(thickness 0.1524)
				)
			)
		)
		(duplicate_pad_numbers_are_jumpers no)
		(fp_rect
			(start -0.2794 0.6477)
			(end 0.2794 -0.6477)
			(stroke
				(width 0)
				(type default)
			)
			(fill no)
			(layer "F.CrtYd")
		)
		(fp_rect
			(start -0.2794 0.6477)
			(end 0.2794 -0.6477)
			(stroke
				(width 0)
				(type default)
			)
			(fill no)
			(layer "F.Fab")
		)
		(pad "1" smd custom
			(at 0 -0.2794 270)
			(size 0.0762 0.0762)
			(layers "F.Cu" "F.Mask" "F.Paste")
			(net "SAS_HDD_RX_P20")
			(options
				(clearance outline)
				(anchor circle)
			)
			(primitives
				(gr_poly
					(pts
						(arc
							(start 0.1524 -0.127)
							(mid 0.137521 -0.162921)
							(end 0.1016 -0.1778)
						)
						(arc
							(start -0.1016 -0.1778)
							(mid -0.137521 -0.162921)
							(end -0.1524 -0.127)
						)
						(arc
							(start -0.1524 0.127)
							(mid -0.137521 0.162921)
							(end -0.1016 0.1778)
						)
						(arc
							(start 0.1016 0.1778)
							(mid 0.137521 0.162921)
							(end 0.1524 0.127)
						)
					)
					(width 0)
					(fill yes)
				)
			)
		)
		(pad "2" smd custom
			(at 0 0.2794 270)
			(size 0.0762 0.0762)
			(layers "F.Cu" "F.Mask" "F.Paste")
			(net "PHY_SCC_A_TO_DRV_A_20_DP")
			(options
				(clearance outline)
				(anchor circle)
			)
			(primitives
				(gr_poly
					(pts
						(arc
							(start 0.1524 -0.127)
							(mid 0.137521 -0.162921)
							(end 0.1016 -0.1778)
						)
						(arc
							(start -0.1016 -0.1778)
							(mid -0.137521 -0.162921)
							(end -0.1524 -0.127)
						)
						(arc
							(start -0.1524 0.127)
							(mid -0.137521 0.162921)
							(end -0.1016 0.1778)
						)
						(arc
							(start 0.1016 0.1778)
							(mid 0.137521 0.162921)
							(end 0.1524 0.127)
						)
					)
					(width 0)
					(fill yes)
				)
			)
		)
	)
)
